# S9S_MB_2U (Grand Teton) — schematic netlist excerpt (pin names and nets, part order shuffled) for the footprints in the layout excerpt that follows; sources: Cadence DE-HDL packaged netlist, KiCad conversion of 03242023_DA0F0TMBIJ0_F0T_Motherboard_J_brd_V01_OCP.brd

R3449  Q_RES  100K 1% CHIP  pkg 0402LF  page 149 : A = GPU_FPGA_BOOT_EN ; B = GND
PR3856  Q_RES  1.33K 1% EMPTY  pkg 0402LF  page 163 : A = GND ; B = P3V3_OCP_ILIMIT_2

(kicad_pcb
	(version 20260206)
	(generator "pcbnew")
	(generator_version "10.0")
	(general
		(thickness 1.6)
		(legacy_teardrops no)
	)
	(paper "A4")
	(title_block
		(title "03242023_DA0F0TMBIJ0_F0T_Motherboard_J_brd_V01_OCP.brd")
		(comment 1 "Grand Teton / footprints 1744-1745 of 6105")
	)
	(layers
		(0 "F.Cu" signal "TOP")
		(4 "In1.Cu" signal "GND")
		(6 "In2.Cu" signal "IN1")
		(8 "In3.Cu" signal "GND1")
		(10 "In4.Cu" signal "IN2")
		(12 "In5.Cu" signal "GND2")
		(14 "In6.Cu" signal "IN3")
		(16 "In7.Cu" signal "GND3")
		(18 "In8.Cu" signal "VCC")
		(20 "In9.Cu" signal "VCC1")
		(22 "In10.Cu" signal "GND4")
		(24 "In11.Cu" signal "IN4")
		(26 "In12.Cu" signal "GND5")
		(28 "In13.Cu" signal "IN5")
		(30 "In14.Cu" signal "GND6")
		(32 "In15.Cu" signal "IN6")
		(34 "In16.Cu" signal "GND7")
		(2 "B.Cu" signal "BOTTOM")
		(9 "F.Adhes" user "F.Adhesive")
		(11 "B.Adhes" user "B.Adhesive")
		(13 "F.Paste" user "Package Geometry/Pastemask Top")
		(15 "B.Paste" user "Package Geometry/Pastemask Bottom")
		(5 "F.SilkS" user "Ref Des/Silkscreen Top")
		(7 "B.SilkS" user "Ref Des/Silkscreen Bottom")
		(1 "F.Mask" user "Board Geometry/Soldermask Top")
		(3 "B.Mask" user "Board Geometry/Soldermask Bottom")
		(17 "Dwgs.User" user "User.Drawings")
		(19 "Cmts.User" user "User.Comments")
		(21 "Eco1.User" user "User.Eco1")
		(23 "Eco2.User" user "User.Eco2")
		(25 "Edge.Cuts" user "Board Geometry/Outline")
		(27 "Margin" user)
		(31 "F.CrtYd" user "Package Geometry/Place Bound Top")
		(29 "B.CrtYd" user "Package Geometry/Place Bound Bottom")
		(35 "F.Fab" user "Ref Des/Assembly Top")
		(33 "B.Fab" user "Ref Des/Assembly Bottom")
	)
	(footprint ""
		(layer "F.Cu")
		(at 67.11188 -54.361588)
		(property "Reference" "PR3856"
			(at 0 0 0)
			(layer "F.SilkS")
			(hide yes)
			(effects
				(font
					(size 1.27 1.27)
				)
			)
		)
		(property "Value" ""
			(at 0 0 0)
			(layer "F.Fab")
			(effects
				(font
					(size 1.27 1.27)
				)
			)
		)
		(duplicate_pad_numbers_are_jumpers no)
		(fp_line
			(start -0.7874 -0.4064)
			(end 0.7874 -0.4064)
			(stroke
				(width 0.1524)
				(type default)
			)
			(layer "F.SilkS")
		)
		(fp_line
			(start -0.7874 0.4064)
			(end -0.7874 -0.4064)
			(stroke
				(width 0.1524)
				(type default)
			)
			(layer "F.SilkS")
		)
		(fp_line
			(start 0.7874 -0.4064)
			(end 0.7874 0.4064)
			(stroke
				(width 0.1524)
				(type default)
			)
			(layer "F.SilkS")
		)
		(fp_line
			(start 0.7874 0.4064)
			(end -0.7874 0.4064)
			(stroke
				(width 0.1524)
				(type default)
			)
			(layer "F.SilkS")
		)
		(fp_line
			(start -0.67945 -0.305054)
			(end -0.12065 -0.305054)
			(stroke
				(width 0.1)
				(type default)
			)
			(layer "F.Fab")
		)
		(fp_line
			(start -0.67945 0.3048)
			(end -0.67945 -0.305054)
			(stroke
				(width 0.1)
				(type default)
			)
			(layer "F.Fab")
		)
		(fp_line
			(start -0.12065 -0.305054)
			(end -0.12065 -0.2794)
			(stroke
				(width 0.1)
				(type default)
			)
			(layer "F.Fab")
		)
		(fp_line
			(start -0.12065 -0.2794)
			(end 0.12065 -0.2794)
			(stroke
				(width 0.1)
				(type default)
			)
			(layer "F.Fab")
		)
		(fp_line
			(start -0.12065 0.2794)
			(end -0.12065 0.3048)
			(stroke
				(width 0.1)
				(type default)
			)
			(layer "F.Fab")
		)
		(fp_line
			(start -0.12065 0.3048)
			(end -0.67945 0.3048)
			(stroke
				(width 0.1)
				(type default)
			)
			(layer "F.Fab")
		)
		(fp_line
			(start 0.120396 0.2794)
			(end -0.12065 0.2794)
			(stroke
				(width 0.1)
				(type default)
			)
			(layer "F.Fab")
		)
		(fp_line
			(start 0.120396 0.3048)
			(end 0.120396 0.2794)
			(stroke
				(width 0.1)
				(type default)
			)
			(layer "F.Fab")
		)
		(fp_line
			(start 0.12065 -0.3048)
			(end 0.67945 -0.3048)
			(stroke
				(width 0.1)
				(type default)
			)
			(layer "F.Fab")
		)
		(fp_line
			(start 0.12065 -0.2794)
			(end 0.12065 -0.3048)
			(stroke
				(width 0.1)
				(type default)
			)
			(layer "F.Fab")
		)
		(fp_line
			(start 0.67945 -0.3048)
			(end 0.67945 0.3048)
			(stroke
				(width 0.1)
				(type default)
			)
			(layer "F.Fab")
		)
		(fp_line
			(start 0.67945 0.3048)
			(end 0.120396 0.3048)
			(stroke
				(width 0.1)
				(type default)
			)
			(layer "F.Fab")
		)
		(pad "1" smd circle
			(at -0.40005 0)
			(size 0 0)
			(layers "F.Cu" "F.Mask" "F.Paste")
			(net "GND")
		)
		(pad "2" smd circle
			(at 0.40005 0)
			(size 0 0)
			(layers "F.Cu" "F.Mask" "F.Paste")
			(net "P3V3_OCP_ILIMIT_2")
		)
	)
	(footprint ""
		(layer "F.Cu")
		(at 163.50488 -438.495948 180)
		(property "Reference" "R3449"
			(at 0 0 180)
			(layer "F.SilkS")
			(hide yes)
			(effects
				(font
					(size 1.27 1.27)
				)
			)
		)
		(property "Value" ""
			(at 0 0 180)
			(layer "F.Fab")
			(effects
				(font
					(size 1.27 1.27)
				)
			)
		)
		(duplicate_pad_numbers_are_jumpers no)
		(fp_line
			(start 0.7874 0.4064)
			(end -0.7874 0.4064)
			(stroke
				(width 0.1524)
				(type default)
			)
			(layer "F.SilkS")
		)
		(fp_line
			(start 0.7874 -0.4064)
			(end 0.7874 0.4064)
			(stroke
				(width 0.1524)
				(type default)
			)
			(layer "F.SilkS")
		)
		(fp_line
			(start -0.7874 0.4064)
			(end -0.7874 -0.4064)
			(stroke
				(width 0.1524)
				(type default)
			)
			(layer "F.SilkS")
		)
		(fp_line
			(start -0.7874 -0.4064)
			(end 0.7874 -0.4064)
			(stroke
				(width 0.1524)
				(type default)
			)
			(layer "F.SilkS")
		)
		(fp_line
			(start 0.67945 0.3048)
			(end 0.120396 0.3048)
			(stroke
				(width 0.1)
				(type default)
			)
			(layer "F.Fab")
		)
		(fp_line
			(start 0.67945 -0.3048)
			(end 0.67945 0.3048)
			(stroke
				(width 0.1)
				(type default)
			)
			(layer "F.Fab")
		)
		(fp_line
			(start 0.12065 -0.2794)
			(end 0.12065 -0.3048)
			(stroke
				(width 0.1)
				(type default)
			)
			(layer "F.Fab")
		)
		(fp_line
			(start 0.12065 -0.3048)
			(end 0.67945 -0.3048)
			(stroke
				(width 0.1)
				(type default)
			)
			(layer "F.Fab")
		)
		(fp_line
			(start 0.120396 0.3048)
			(end 0.120396 0.2794)
			(stroke
				(width 0.1)
				(type default)
			)
			(layer "F.Fab")
		)
		(fp_line
			(start 0.120396 0.2794)
			(end -0.12065 0.2794)
			(stroke
				(width 0.1)
				(type default)
			)
			(layer "F.Fab")
		)
		(fp_line
			(start -0.12065 0.3048)
			(end -0.67945 0.3048)
			(stroke
				(width 0.1)
				(type default)
			)
			(layer "F.Fab")
		)
		(fp_line
			(start -0.12065 0.2794)
			(end -0.12065 0.3048)
			(stroke
				(width 0.1)
				(type default)
			)
			(layer "F.Fab")
		)
		(fp_line
			(start -0.12065 -0.2794)
			(end 0.12065 -0.2794)
			(stroke
				(width 0.1)
				(type default)
			)
			(layer "F.Fab")
		)
		(fp_line
			(start -0.12065 -0.305054)
			(end -0.12065 -0.2794)
			(stroke
				(width 0.1)
				(type default)
			)
			(layer "F.Fab")
		)
		(fp_line
			(start -0.67945 0.3048)
			(end -0.67945 -0.305054)
			(stroke
				(width 0.1)
				(type default)
			)
			(layer "F.Fab")
		)
		(fp_line
			(start -0.67945 -0.305054)
			(end -0.12065 -0.305054)
			(stroke
				(width 0.1)
				(type default)
			)
			(layer "F.Fab")
		)
		(pad "1" smd circle
			(at -0.40005 0 180)
			(size 0 0)
			(layers "F.Cu" "F.Mask" "F.Paste")
			(net "GPU_FPGA_BOOT_EN")
		)
		(pad "2" smd circle
			(at 0.40005 0 180)
			(size 0 0)
			(layers "F.Cu" "F.Mask" "F.Paste")
			(net "GND")
		)
	)
)
